(kicad_pcb
	(version 20241229)
	(generator "pcbnew")
	(generator_version "9.0")
	(general
		(thickness 1.6642)
		(legacy_teardrops no)
	)
	(paper "A3")
	(title_block
		(title "PolarFire SoM")
		(date "2025-07-22")
		(rev "1.1.4")
		(company "Antmicro Ltd")
		(comment 1 "www.antmicro.com")
		(comment 9 "footprints 133-136 of 470")
	)
	(layers
		(0 "F.Cu" mixed)
		(4 "In1.Cu" power)
		(6 "In2.Cu" signal)
		(8 "In3.Cu" power)
		(10 "In4.Cu" signal)
		(12 "In5.Cu" power)
		(14 "In6.Cu" power)
		(16 "In7.Cu" signal)
		(18 "In8.Cu" power)
		(20 "In9.Cu" signal)
		(22 "In10.Cu" power)
		(24 "In11.Cu" signal)
		(26 "In12.Cu" signal)
		(2 "B.Cu" mixed)
		(9 "F.Adhes" user "F.Adhesive")
		(11 "B.Adhes" user "B.Adhesive")
		(13 "F.Paste" user)
		(15 "B.Paste" user)
		(5 "F.SilkS" user "F.Silkscreen")
		(7 "B.SilkS" user "B.Silkscreen")
		(1 "F.Mask" user)
		(3 "B.Mask" user)
		(17 "Dwgs.User" user "User.Drawings")
		(19 "Cmts.User" user "User.Comments")
		(21 "Eco1.User" user "User.Eco1")
		(23 "Eco2.User" user "User.Eco2")
		(25 "Edge.Cuts" user)
		(27 "Margin" user)
		(31 "F.CrtYd" user "F.Courtyard")
		(29 "B.CrtYd" user "B.Courtyard")
		(35 "F.Fab" user)
		(33 "B.Fab" user)
	)
	(footprint "antmicro-footprints:C_0402_1005Metric"
		(layer "B.Cu")
		(at 212.1925 134.697)
		(descr "Capacitor SMD 0402")
		(tags "capacitor SMD 0402")
		(property "Reference" "C78"
			(at -0.4175 2.528 0)
			(layer "B.SilkS")
			(effects
				(font
					(size 0.7 0.7)
					(thickness 0.15)
				)
				(justify right bottom mirror)
			)
		)
		(property "Value" "C_100n_0402"
			(at -1.022927 -2.155213 0)
			(layer "B.Fab")
			(hide yes)
			(effects
				(font
					(size 0.7 0.7)
					(thickness 0.15)
				)
				(justify right bottom mirror)
			)
		)
		(property "Datasheet" "https://www.murata.com/products/productdetail?partno=GRM155R61H104KE14%23"
			(at 0 0 0)
			(layer "F.Fab")
			(hide yes)
			(effects
				(font
					(size 1.27 1.27)
					(thickness 0.15)
				)
			)
		)
		(property "Description" "SMD Multilayer Ceramic Capacitor, 0.1 µF, 50 V, 0402 [1005 Metric], ± 10%, X5R, GRM Series"
			(at 0 0 0)
			(layer "F.Fab")
			(hide yes)
			(effects
				(font
					(size 1.27 1.27)
					(thickness 0.15)
				)
			)
		)
		(property "Author" "Antmicro"
			(at 0 0 0)
			(layer "B.Fab")
			(hide yes)
			(effects
				(font
					(size 1 1)
					(thickness 0.15)
				)
				(justify mirror)
			)
		)
		(property "Dielectric" "X5R"
			(at 0 0 0)
			(layer "B.Fab")
			(hide yes)
			(effects
				(font
					(size 1 1)
					(thickness 0.15)
				)
				(justify mirror)
			)
		)
		(property "License" "Apache-2.0"
			(at 0 0 0)
			(layer "B.Fab")
			(hide yes)
			(effects
				(font
					(size 1 1)
					(thickness 0.15)
				)
				(justify mirror)
			)
		)
		(property "MPN" "GRM155R61H104KE14D"
			(at 0 0 0)
			(layer "B.Fab")
			(hide yes)
			(effects
				(font
					(size 1 1)
					(thickness 0.15)
				)
				(justify mirror)
			)
		)
		(property "Manufacturer" "Murata"
			(at 0 0 0)
			(layer "B.Fab")
			(hide yes)
			(effects
				(font
					(size 1 1)
					(thickness 0.15)
				)
				(justify mirror)
			)
		)
		(property "Public" ""
			(at 0 0 0)
			(layer "B.Fab")
			(hide yes)
			(effects
				(font
					(size 1 1)
					(thickness 0.15)
				)
				(justify mirror)
			)
		)
		(property "Val" "100n"
			(at 0 0 0)
			(layer "B.Fab")
			(hide yes)
			(effects
				(font
					(size 1 1)
					(thickness 0.15)
				)
				(justify mirror)
			)
		)
		(property "Voltage" "50V"
			(at 0 0 0)
			(layer "B.Fab")
			(hide yes)
			(effects
				(font
					(size 1 1)
					(thickness 0.15)
				)
				(justify mirror)
			)
		)
		(sheetname "/Memory/")
		(sheetfile "memory.kicad_sch")
		(attr smd)
		(fp_rect
			(start -0.925 0.47)
			(end 0.925 -0.47)
			(stroke
				(width 0.05)
				(type default)
			)
			(fill no)
			(layer "B.CrtYd")
		)
		(fp_line
			(start -0.494 -0.248)
			(end -0.494 0.25)
			(stroke
				(width 0.15)
				(type solid)
			)
			(layer "B.Fab")
		)
		(fp_line
			(start -0.494 0.25)
			(end 0.504 0.25)
			(stroke
				(width 0.15)
				(type solid)
			)
			(layer "B.Fab")
		)
		(fp_line
			(start 0.504 -0.248)
			(end -0.494 -0.248)
			(stroke
				(width 0.15)
				(type solid)
			)
			(layer "B.Fab")
		)
		(fp_line
			(start 0.504 0.25)
			(end 0.504 -0.248)
			(stroke
				(width 0.15)
				(type solid)
			)
			(layer "B.Fab")
		)
		(fp_text user "License: Apache-2.0"
			(at -0.939 -5.799 180)
			(layer "B.Fab")
			(effects
				(font
					(size 0.7 0.7)
					(thickness 0.15)
				)
				(justify left bottom mirror)
			)
		)
		(fp_text user "${REFERENCE}"
			(at -0.939 -4.599 180)
			(layer "B.Fab")
			(effects
				(font
					(size 0.7 0.7)
					(thickness 0.15)
				)
				(justify left bottom mirror)
			)
		)
		(fp_text user "Author: Antmicro"
			(at -0.939 -3.399 180)
			(layer "B.Fab")
			(effects
				(font
					(size 0.7 0.7)
					(thickness 0.15)
				)
				(justify left bottom mirror)
			)
		)
		(pad "1" smd roundrect
			(at -0.48 0)
			(size 0.59 0.64)
			(layers "B.Cu" "B.Mask" "B.Paste")
			(roundrect_rratio 0.25)
			(net 417 "GND")
			(pintype "passive")
		)
		(pad "2" smd roundrect
			(at 0.48 0)
			(size 0.59 0.64)
			(layers "B.Cu" "B.Mask" "B.Paste")
			(roundrect_rratio 0.25)
			(net 137 "SD_VDD")
			(pintype "passive")
		)
	)
	(footprint "antmicro-footprints:C_0603_1608Metric"
		(layer "B.Cu")
		(at 193.5 135.52)
		(descr "Capacitor SMD 0603")
		(tags "capacitor 0603")
		(property "Reference" "C29"
			(at -1.4 1.53 0)
			(layer "B.SilkS")
			(effects
				(font
					(size 0.7 0.7)
					(thickness 0.15)
				)
				(justify right bottom mirror)
			)
		)
		(property "Value" "C_47u_0603"
			(at -1.42757 -1.770288 0)
			(layer "B.Fab")
			(hide yes)
			(effects
				(font
					(size 0.7 0.7)
					(thickness 0.15)
				)
				(justify right bottom mirror)
			)
		)
		(property "Datasheet" "https://www.murata.com/products/productdetail?partno=GRM188R60J476ME15%23"
			(at 0 0 0)
			(layer "F.Fab")
			(hide yes)
			(effects
				(font
					(size 1.27 1.27)
					(thickness 0.15)
				)
			)
		)
		(property "Description" "SMD Multilayer Ceramic Capacitor, 47 µF, 6.3 V, 0603 [1608 Metric], ± 20%, X5R, GRM Series"
			(at 0 0 0)
			(layer "F.Fab")
			(hide yes)
			(effects
				(font
					(size 1.27 1.27)
					(thickness 0.15)
				)
			)
		)
		(property "Author" "Antmicro"
			(at 0 0 0)
			(layer "B.Fab")
			(hide yes)
			(effects
				(font
					(size 1 1)
					(thickness 0.15)
				)
				(justify mirror)
			)
		)
		(property "Capacitance" "47u"
			(at 0 0 0)
			(layer "B.Fab")
			(hide yes)
			(effects
				(font
					(size 1 1)
					(thickness 0.15)
				)
				(justify mirror)
			)
		)
		(property "Dielectric" "X7R"
			(at 0 0 0)
			(layer "B.Fab")
			(hide yes)
			(effects
				(font
					(size 1 1)
					(thickness 0.15)
				)
				(justify mirror)
			)
		)
		(property "License" "Apache-2.0"
			(at 0 0 0)
			(layer "B.Fab")
			(hide yes)
			(effects
				(font
					(size 1 1)
					(thickness 0.15)
				)
				(justify mirror)
			)
		)
		(property "MPN" "GRM188R60J476ME15D"
			(at 0 0 0)
			(layer "B.Fab")
			(hide yes)
			(effects
				(font
					(size 1 1)
					(thickness 0.15)
				)
				(justify mirror)
			)
		)
		(property "Manufacturer" "Murata"
			(at 0 0 0)
			(layer "B.Fab")
			(hide yes)
			(effects
				(font
					(size 1 1)
					(thickness 0.15)
				)
				(justify mirror)
			)
		)
		(property "Public" ""
			(at 0 0 0)
			(layer "B.Fab")
			(hide yes)
			(effects
				(font
					(size 1 1)
					(thickness 0.15)
				)
				(justify mirror)
			)
		)
		(property "Val" "47u"
			(at 0 0 0)
			(layer "B.Fab")
			(hide yes)
			(effects
				(font
					(size 1 1)
					(thickness 0.15)
				)
				(justify mirror)
			)
		)
		(property "Voltage" "50V"
			(at 0 0 0)
			(layer "B.Fab")
			(hide yes)
			(effects
				(font
					(size 1 1)
					(thickness 0.15)
				)
				(justify mirror)
			)
		)
		(sheetname "/FPGA Supply/")
		(sheetfile "fpga-supply.kicad_sch")
		(attr smd)
		(fp_line
			(start -0.15 -0.4)
			(end 0.15 -0.4)
			(stroke
				(width 0.15)
				(type solid)
			)
			(layer "B.SilkS")
		)
		(fp_line
			(start -0.15 0.4)
			(end 0.15 0.4)
			(stroke
				(width 0.15)
				(type solid)
			)
			(layer "B.SilkS")
		)
		(fp_rect
			(start -1.25 0.65)
			(end 1.25 -0.65)
			(stroke
				(width 0.05)
				(type solid)
			)
			(fill no)
			(layer "B.CrtYd")
		)
		(fp_rect
			(start -0.8 0.4)
			(end 0.8 -0.4)
			(stroke
				(width 0.15)
				(type solid)
			)
			(fill no)
			(layer "B.Fab")
		)
		(fp_text user "License: Apache-2.0"
			(at -1.682 -5.895 180)
			(layer "B.Fab")
			(effects
				(font
					(size 0.7 0.7)
					(thickness 0.15)
				)
				(justify left bottom mirror)
			)
		)
		(fp_text user "${REFERENCE}"
			(at -1.682 -3.895 180)
			(layer "B.Fab")
			(effects
				(font
					(size 0.7 0.7)
					(thickness 0.15)
				)
				(justify left bottom mirror)
			)
		)
		(fp_text user "Author: Antmicro"
			(at -1.682 -4.894 180)
			(layer "B.Fab")
			(effects
				(font
					(size 0.7 0.7)
					(thickness 0.15)
				)
				(justify left bottom mirror)
			)
		)
		(pad "1" smd roundrect
			(at -0.7 0)
			(size 0.8 1)
			(layers "B.Cu" "B.Mask" "B.Paste")
			(roundrect_rratio 0.2)
			(net 417 "GND")
			(pintype "passive")
		)
		(pad "2" smd roundrect
			(at 0.7 0)
			(size 0.8 1)
			(layers "B.Cu" "B.Mask" "B.Paste")
			(roundrect_rratio 0.2)
			(net 418 "+2V5")
			(pintype "passive")
		)
	)
	(footprint "antmicro-footprints:C_0402_1005Metric"
		(layer "B.Cu")
		(at 175.28 124.9 -90)
		(descr "Capacitor SMD 0402")
		(tags "capacitor SMD 0402")
		(property "Reference" "C118"
			(at -1.04 -4.23 180)
			(layer "B.SilkS")
			(effects
				(font
					(size 0.7 0.7)
					(thickness 0.15)
				)
				(justify left bottom mirror)
			)
		)
		(property "Value" "C_1u_0402"
			(at -1.022927 -2.155213 90)
			(layer "B.Fab")
			(hide yes)
			(effects
				(font
					(size 0.7 0.7)
					(thickness 0.15)
				)
				(justify left bottom mirror)
			)
		)
		(property "Datasheet" "https://product.tdk.com/en/search/capacitor/ceramic/mlcc/info?part_no=C1005X6S1A105K050BC"
			(at 0 0 270)
			(layer "F.Fab")
			(hide yes)
			(effects
				(font
					(size 1.27 1.27)
					(thickness 0.15)
				)
			)
		)
		(property "Description" "SMD Multilayer Ceramic Capacitor, 1 µF, 10 V, 0402 [1005 Metric], ± 10%, X6S, C"
			(at 0 0 270)
			(layer "F.Fab")
			(hide yes)
			(effects
				(font
					(size 1.27 1.27)
					(thickness 0.15)
				)
			)
		)
		(property "Author" "Antmicro"
			(at 50.38 300.18 0)
			(layer "B.Fab")
			(hide yes)
			(effects
				(font
					(size 1 1)
					(thickness 0.15)
				)
				(justify mirror)
			)
		)
		(property "Dielectric" "X5R"
			(at 50.38 300.18 0)
			(layer "B.Fab")
			(hide yes)
			(effects
				(font
					(size 1 1)
					(thickness 0.15)
				)
				(justify mirror)
			)
		)
		(property "License" "Apache-2.0"
			(at 50.38 300.18 0)
			(layer "B.Fab")
			(hide yes)
			(effects
				(font
					(size 1 1)
					(thickness 0.15)
				)
				(justify mirror)
			)
		)
		(property "MPN" "C1005X6S1A105K050BC"
			(at 50.38 300.18 0)
			(layer "B.Fab")
			(hide yes)
			(effects
				(font
					(size 1 1)
					(thickness 0.15)
				)
				(justify mirror)
			)
		)
		(property "Manufacturer" "TDK"
			(at 50.38 300.18 0)
			(layer "B.Fab")
			(hide yes)
			(effects
				(font
					(size 1 1)
					(thickness 0.15)
				)
				(justify mirror)
			)
		)
		(property "Public" ""
			(at 50.38 300.18 0)
			(layer "B.Fab")
			(hide yes)
			(effects
				(font
					(size 1 1)
					(thickness 0.15)
				)
				(justify mirror)
			)
		)
		(property "Val" "1u"
			(at 50.38 300.18 0)
			(layer "B.Fab")
			(hide yes)
			(effects
				(font
					(size 1 1)
					(thickness 0.15)
				)
				(justify mirror)
			)
		)
		(property "Voltage" "16V"
			(at 50.38 300.18 0)
			(layer "B.Fab")
			(hide yes)
			(effects
				(font
					(size 1 1)
					(thickness 0.15)
				)
				(justify mirror)
			)
		)
		(sheetname "/LPDDR4/")
		(sheetfile "lpddr.kicad_sch")
		(attr smd)
		(fp_rect
			(start -0.925 0.47)
			(end 0.925 -0.47)
			(stroke
				(width 0.05)
				(type default)
			)
			(fill no)
			(layer "B.CrtYd")
		)
		(fp_line
			(start -0.494 0.25)
			(end 0.504 0.25)
			(stroke
				(width 0.15)
				(type solid)
			)
			(layer "B.Fab")
		)
		(fp_line
			(start 0.504 0.25)
			(end 0.504 -0.248)
			(stroke
				(width 0.15)
				(type solid)
			)
			(layer "B.Fab")
		)
		(fp_line
			(start -0.494 -0.248)
			(end -0.494 0.25)
			(stroke
				(width 0.15)
				(type solid)
			)
			(layer "B.Fab")
		)
		(fp_line
			(start 0.504 -0.248)
			(end -0.494 -0.248)
			(stroke
				(width 0.15)
				(type solid)
			)
			(layer "B.Fab")
		)
		(fp_text user "${REFERENCE}"
			(at -0.939 -4.599 90)
			(layer "B.Fab")
			(effects
				(font
					(size 0.7 0.7)
					(thickness 0.15)
				)
				(justify left bottom mirror)
			)
		)
		(fp_text user "Author: Antmicro"
			(at -0.939 -3.399 90)
			(layer "B.Fab")
			(effects
				(font
					(size 0.7 0.7)
					(thickness 0.15)
				)
				(justify left bottom mirror)
			)
		)
		(fp_text user "License: Apache-2.0"
			(at -0.939 -5.799 90)
			(layer "B.Fab")
			(effects
				(font
					(size 0.7 0.7)
					(thickness 0.15)
				)
				(justify left bottom mirror)
			)
		)
		(pad "1" smd roundrect
			(at -0.48 0 270)
			(size 0.59 0.64)
			(layers "B.Cu" "B.Mask" "B.Paste")
			(roundrect_rratio 0.25)
			(net 417 "GND")
			(pintype "passive")
		)
		(pad "2" smd roundrect
			(at 0.48 0 270)
			(size 0.59 0.64)
			(layers "B.Cu" "B.Mask" "B.Paste")
			(roundrect_rratio 0.25)
			(net 48 "+1V8")
			(pintype "passive")
		)
	)
	(footprint "antmicro-footprints:C_0402_1005Metric"
		(layer "B.Cu")
		(at 218.725 144.8875 -90)
		(descr "Capacitor SMD 0402")
		(tags "capacitor SMD 0402")
		(property "Reference" "C231"
			(at -9.9125 -7.15 90)
			(layer "B.SilkS")
			(effects
				(font
					(size 0.7 0.7)
					(thickness 0.15)
				)
				(justify left bottom mirror)
			)
		)
		(property "Value" "C_100n_0402"
			(at -1.022927 -2.155213 90)
			(layer "B.Fab")
			(hide yes)
			(effects
				(font
					(size 0.7 0.7)
					(thickness 0.15)
				)
				(justify left bottom mirror)
			)
		)
		(property "Datasheet" "https://www.murata.com/products/productdetail?partno=GRM155R61H104KE14%23"
			(at 0 0 270)
			(layer "F.Fab")
			(hide yes)
			(effects
				(font
					(size 1.27 1.27)
					(thickness 0.15)
				)
			)
		)
		(property "Description" "SMD Multilayer Ceramic Capacitor, 0.1 µF, 50 V, 0402 [1005 Metric], ± 10%, X5R, GRM Series"
			(at 0 0 270)
			(layer "F.Fab")
			(hide yes)
			(effects
				(font
					(size 1.27 1.27)
					(thickness 0.15)
				)
			)
		)
		(property "Author" "Antmicro"
			(at 73.8375 363.6125 0)
			(layer "B.Fab")
			(hide yes)
			(effects
				(font
					(size 1 1)
					(thickness 0.15)
				)
				(justify mirror)
			)
		)
		(property "Dielectric" "X5R"
			(at 73.8375 363.6125 0)
			(layer "B.Fab")
			(hide yes)
			(effects
				(font
					(size 1 1)
					(thickness 0.15)
				)
				(justify mirror)
			)
		)
		(property "License" "Apache-2.0"
			(at 73.8375 363.6125 0)
			(layer "B.Fab")
			(hide yes)
			(effects
				(font
					(size 1 1)
					(thickness 0.15)
				)
				(justify mirror)
			)
		)
		(property "MPN" "GRM155R61H104KE14D"
			(at 73.8375 363.6125 0)
			(layer "B.Fab")
			(hide yes)
			(effects
				(font
					(size 1 1)
					(thickness 0.15)
				)
				(justify mirror)
			)
		)
		(property "Manufacturer" "Murata"
			(at 73.8375 363.6125 0)
			(layer "B.Fab")
			(hide yes)
			(effects
				(font
					(size 1 1)
					(thickness 0.15)
				)
				(justify mirror)
			)
		)
		(property "Public" ""
			(at 73.8375 363.6125 0)
			(layer "B.Fab")
			(hide yes)
			(effects
				(font
					(size 1 1)
					(thickness 0.15)
				)
				(justify mirror)
			)
		)
		(property "Val" "100n"
			(at 73.8375 363.6125 0)
			(layer "B.Fab")
			(hide yes)
			(effects
				(font
					(size 1 1)
					(thickness 0.15)
				)
				(justify mirror)
			)
		)
		(property "Voltage" "50V"
			(at 73.8375 363.6125 0)
			(layer "B.Fab")
			(hide yes)
			(effects
				(font
					(size 1 1)
					(thickness 0.15)
				)
				(justify mirror)
			)
		)
		(sheetname "/WiFi_Bluetooth/")
		(sheetfile "wifi_bt.kicad_sch")
		(attr smd)
		(fp_rect
			(start -0.925 0.47)
			(end 0.925 -0.47)
			(stroke
				(width 0.05)
				(type default)
			)
			(fill no)
			(layer "B.CrtYd")
		)
		(fp_line
			(start -0.494 0.25)
			(end 0.504 0.25)
			(stroke
				(width 0.15)
				(type solid)
			)
			(layer "B.Fab")
		)
		(fp_line
			(start 0.504 0.25)
			(end 0.504 -0.248)
			(stroke
				(width 0.15)
				(type solid)
			)
			(layer "B.Fab")
		)
		(fp_line
			(start -0.494 -0.248)
			(end -0.494 0.25)
			(stroke
				(width 0.15)
				(type solid)
			)
			(layer "B.Fab")
		)
		(fp_line
			(start 0.504 -0.248)
			(end -0.494 -0.248)
			(stroke
				(width 0.15)
				(type solid)
			)
			(layer "B.Fab")
		)
		(fp_text user "License: Apache-2.0"
			(at -0.939 -5.799 90)
			(layer "B.Fab")
			(effects
				(font
					(size 0.7 0.7)
					(thickness 0.15)
				)
				(justify left bottom mirror)
			)
		)
		(fp_text user "Author: Antmicro"
			(at -0.939 -3.399 90)
			(layer "B.Fab")
			(effects
				(font
					(size 0.7 0.7)
					(thickness 0.15)
				)
				(justify left bottom mirror)
			)
		)
		(fp_text user "${REFERENCE}"
			(at -0.939 -4.599 90)
			(layer "B.Fab")
			(effects
				(font
					(size 0.7 0.7)
					(thickness 0.15)
				)
				(justify left bottom mirror)
			)
		)
		(pad "1" smd roundrect
			(at -0.48 0 270)
			(size 0.59 0.64)
			(layers "B.Cu" "B.Mask" "B.Paste")
			(roundrect_rratio 0.25)
			(net 417 "GND")
			(pintype "passive")
		)
		(pad "2" smd roundrect
			(at 0.48 0 270)
			(size 0.59 0.64)
			(layers "B.Cu" "B.Mask" "B.Paste")
			(roundrect_rratio 0.25)
			(net 50 "+3V3")
			(pintype "passive")
		)
	)
)
